(kicad_pcb
	(version 20241229)
	(generator "pcbnew")
	(generator_version "9.0")
	(general
		(thickness 1.6296)
		(legacy_teardrops no)
	)
	(paper "A3")
	(title_block
		(title "Thunderbolt to 10GbE adapter")
		(date "2026-04-21")
		(rev "1.1.0")
		(company "Antmicro Ltd")
		(comment 1 "www.antmicro.com")
		(comment 9 "footprints 5-8 of 703")
	)
	(layers
		(0 "F.Cu" signal)
		(4 "In1.Cu" signal)
		(6 "In2.Cu" signal)
		(8 "In3.Cu" signal)
		(10 "In4.Cu" signal)
		(12 "In5.Cu" signal)
		(14 "In6.Cu" signal)
		(2 "B.Cu" signal)
		(9 "F.Adhes" user "F.Adhesive")
		(11 "B.Adhes" user "B.Adhesive")
		(13 "F.Paste" user)
		(15 "B.Paste" user)
		(5 "F.SilkS" user "F.Silkscreen")
		(7 "B.SilkS" user "B.Silkscreen")
		(1 "F.Mask" user)
		(3 "B.Mask" user)
		(17 "Dwgs.User" user "User.Drawings")
		(19 "Cmts.User" user "User.Comments")
		(21 "Eco1.User" user "User.Eco1")
		(23 "Eco2.User" user "User.Eco2")
		(25 "Edge.Cuts" user)
		(27 "Margin" user)
		(31 "F.CrtYd" user "F.Courtyard")
		(29 "B.CrtYd" user "B.Courtyard")
		(35 "F.Fab" user)
		(33 "B.Fab" user)
	)
	(footprint "antmicro-footprints:C_0402_1005Metric"
		(layer "F.Cu")
		(at 153.8 46.9)
		(descr "Capacitor SMD 0402")
		(tags "capacitor SMD 0402")
		(property "Reference" "C312"
			(at -3.8 0.2 0)
			(layer "F.SilkS")
			(effects
				(font
					(size 0.7 0.7)
					(thickness 0.15)
				)
				(justify left bottom)
			)
		)
		(property "Value" "C_100n_0402"
			(at -1.022927 2.155213 0)
			(layer "F.Fab")
			(effects
				(font
					(size 0.7 0.7)
					(thickness 0.15)
				)
				(justify left bottom)
			)
		)
		(property "Datasheet" "https://www.murata.com/products/productdetail?partno=GRM155R61H104KE14%23"
			(at 0 0 0)
			(layer "F.Fab")
			(hide yes)
			(effects
				(font
					(size 1.27 1.27)
					(thickness 0.15)
				)
			)
		)
		(property "Description" "SMD Multilayer Ceramic Capacitor, 0.1 µF, 50 V, 0402 [1005 Metric], ± 10%, X5R, GRM Series"
			(at 0 0 0)
			(layer "F.Fab")
			(hide yes)
			(effects
				(font
					(size 1.27 1.27)
					(thickness 0.15)
				)
			)
		)
		(property "MPN" "GRM155R61H104KE14D"
			(at 0 0 0)
			(unlocked yes)
			(layer "F.Fab")
			(hide yes)
			(effects
				(font
					(size 1 1)
					(thickness 0.15)
				)
			)
		)
		(property "Manufacturer" "Murata"
			(at 0 0 0)
			(unlocked yes)
			(layer "F.Fab")
			(hide yes)
			(effects
				(font
					(size 1 1)
					(thickness 0.15)
				)
			)
		)
		(property "License" "Apache-2.0"
			(at 0 0 0)
			(unlocked yes)
			(layer "F.Fab")
			(hide yes)
			(effects
				(font
					(size 1 1)
					(thickness 0.15)
				)
			)
		)
		(property "Author" "Antmicro"
			(at 0 0 0)
			(unlocked yes)
			(layer "F.Fab")
			(hide yes)
			(effects
				(font
					(size 1 1)
					(thickness 0.15)
				)
			)
		)
		(property "Val" "100n"
			(at 0 0 0)
			(unlocked yes)
			(layer "F.Fab")
			(hide yes)
			(effects
				(font
					(size 1 1)
					(thickness 0.15)
				)
			)
		)
		(property "Voltage" "50V"
			(at 0 0 0)
			(unlocked yes)
			(layer "F.Fab")
			(hide yes)
			(effects
				(font
					(size 1 1)
					(thickness 0.15)
				)
			)
		)
		(property "Dielectric" "X5R"
			(at 0 0 0)
			(unlocked yes)
			(layer "F.Fab")
			(hide yes)
			(effects
				(font
					(size 1 1)
					(thickness 0.15)
				)
			)
		)
		(sheetname "/Power input/")
		(sheetfile "power_input.kicad_sch")
		(attr smd)
		(fp_rect
			(start -0.925 -0.47)
			(end 0.925 0.47)
			(stroke
				(width 0.05)
				(type default)
			)
			(fill no)
			(layer "F.CrtYd")
		)
		(fp_line
			(start -0.494 -0.25)
			(end 0.504 -0.25)
			(stroke
				(width 0.15)
				(type solid)
			)
			(layer "F.Fab")
		)
		(fp_line
			(start -0.494 0.248)
			(end -0.494 -0.25)
			(stroke
				(width 0.15)
				(type solid)
			)
			(layer "F.Fab")
		)
		(fp_line
			(start 0.504 -0.25)
			(end 0.504 0.248)
			(stroke
				(width 0.15)
				(type solid)
			)
			(layer "F.Fab")
		)
		(fp_line
			(start 0.504 0.248)
			(end -0.494 0.248)
			(stroke
				(width 0.15)
				(type solid)
			)
			(layer "F.Fab")
		)
		(fp_text user "${REFERENCE}"
			(at -0.939 4.599 0)
			(layer "F.Fab")
			(effects
				(font
					(size 0.7 0.7)
					(thickness 0.15)
				)
				(justify left bottom)
			)
		)
		(fp_text user "License: Apache-2.0"
			(at -0.939 5.799 0)
			(layer "F.Fab")
			(effects
				(font
					(size 0.7 0.7)
					(thickness 0.15)
				)
				(justify left bottom)
			)
		)
		(fp_text user "Author: Antmicro"
			(at -0.939 3.399 0)
			(layer "F.Fab")
			(effects
				(font
					(size 0.7 0.7)
					(thickness 0.15)
				)
				(justify left bottom)
			)
		)
		(pad "1" smd roundrect
			(at -0.48 0)
			(size 0.59 0.64)
			(layers "F.Cu" "F.Mask" "F.Paste")
			(roundrect_rratio 0.25)
			(net 23 "GND")
			(pintype "passive")
		)
		(pad "2" smd roundrect
			(at 0.48 0)
			(size 0.59 0.64)
			(layers "F.Cu" "F.Mask" "F.Paste")
			(roundrect_rratio 0.25)
			(net 344 "/Power input/5V_EN")
			(pintype "passive")
		)
	)
	(footprint "antmicro-footprints:C_0603_1608Metric_EIA"
		(layer "F.Cu")
		(at 162.6 114.35)
		(descr "Capacitor SMD 0603, IPC-7351 Density Level A")
		(tags "Capacitor 0603")
		(property "Reference" "C107"
			(at 12.450003 16.600001 0)
			(layer "F.SilkS")
			(effects
				(font
					(size 0.7 0.7)
					(thickness 0.15)
				)
			)
		)
		(property "Value" "C_22u_16V_0603"
			(at -1.42757 1.770288 0)
			(layer "F.Fab")
			(effects
				(font
					(size 0.7 0.7)
					(thickness 0.15)
				)
				(justify left bottom)
			)
		)
		(property "Datasheet" "https://product.samsungsem.com/mlcc/CL10A226MO7JZN.do"
			(at 0 0 0)
			(layer "F.Fab")
			(hide yes)
			(effects
				(font
					(size 1.27 1.27)
					(thickness 0.15)
				)
			)
		)
		(property "Description" "SMD Multilayer Ceramic Capacitor"
			(at 0 0 0)
			(layer "F.Fab")
			(hide yes)
			(effects
				(font
					(size 1.27 1.27)
					(thickness 0.15)
				)
			)
		)
		(property "MPN" "CL10A226MO7JZNC"
			(at 0 0 0)
			(unlocked yes)
			(layer "F.Fab")
			(hide yes)
			(effects
				(font
					(size 1 1)
					(thickness 0.15)
				)
			)
		)
		(property "Manufacturer" "Samsung Electro-Mechanics"
			(at 0 0 0)
			(unlocked yes)
			(layer "F.Fab")
			(hide yes)
			(effects
				(font
					(size 1 1)
					(thickness 0.15)
				)
			)
		)
		(property "License" "Apache-2.0"
			(at 0 0 0)
			(unlocked yes)
			(layer "F.Fab")
			(hide yes)
			(effects
				(font
					(size 1 1)
					(thickness 0.15)
				)
			)
		)
		(property "Author" "Antmicro"
			(at 0 0 0)
			(unlocked yes)
			(layer "F.Fab")
			(hide yes)
			(effects
				(font
					(size 1 1)
					(thickness 0.15)
				)
			)
		)
		(property "Val" "22u"
			(at 0 0 0)
			(unlocked yes)
			(layer "F.Fab")
			(hide yes)
			(effects
				(font
					(size 1 1)
					(thickness 0.15)
				)
			)
		)
		(property "Voltage" "16V"
			(at 0 0 0)
			(unlocked yes)
			(layer "F.Fab")
			(hide yes)
			(effects
				(font
					(size 1 1)
					(thickness 0.15)
				)
			)
		)
		(property "Dielectric" ""
			(at 0 0 0)
			(unlocked yes)
			(layer "F.Fab")
			(hide yes)
			(effects
				(font
					(size 1 1)
					(thickness 0.15)
				)
			)
		)
		(sheetname "/X710 DCDC converters/")
		(sheetfile "DCDC_converters_X710.kicad_sch")
		(attr smd)
		(fp_line
			(start -0.15 -0.55)
			(end 0.15 -0.55)
			(stroke
				(width 0.15)
				(type solid)
			)
			(layer "F.SilkS")
		)
		(fp_line
			(start -0.15 0.55)
			(end 0.15 0.55)
			(stroke
				(width 0.15)
				(type solid)
			)
			(layer "F.SilkS")
		)
		(fp_rect
			(start -1.25 -0.65)
			(end 1.25 0.65)
			(stroke
				(width 0.05)
				(type solid)
			)
			(fill no)
			(layer "F.CrtYd")
		)
		(fp_rect
			(start -0.8 -0.45)
			(end 0.8 0.45)
			(stroke
				(width 0.15)
				(type solid)
			)
			(fill no)
			(layer "F.Fab")
		)
		(fp_text user "License: Apache-2.0"
			(at -1.682 5.895 0)
			(layer "F.Fab")
			(effects
				(font
					(size 0.7 0.7)
					(thickness 0.15)
				)
				(justify left bottom)
			)
		)
		(fp_text user "${REFERENCE}"
			(at -1.682 3.895 0)
			(layer "F.Fab")
			(effects
				(font
					(size 0.7 0.7)
					(thickness 0.15)
				)
				(justify left bottom)
			)
		)
		(fp_text user "Author: Antmicro"
			(at -1.682 4.894 0)
			(layer "F.Fab")
			(effects
				(font
					(size 0.7 0.7)
					(thickness 0.15)
				)
				(justify left bottom)
			)
		)
		(pad "1" smd roundrect
			(at -0.7 0)
			(size 0.8 1.1)
			(layers "F.Cu" "F.Mask" "F.Paste")
			(roundrect_rratio 0.2)
			(net 23 "GND")
			(pintype "passive")
		)
		(pad "2" smd roundrect
			(at 0.7 0)
			(size 0.8 1.1)
			(layers "F.Cu" "F.Mask" "F.Paste")
			(roundrect_rratio 0.2)
			(net 40 "+5V")
			(pintype "passive")
		)
	)
	(footprint "antmicro-footprints:R_0402_1005Metric"
		(layer "F.Cu")
		(at 155.255 67.124999 -90)
		(descr "Resistor SMD 0402")
		(tags "resistor SMD 0402")
		(property "Reference" "R144"
			(at -12.324999 -20.295 270)
			(layer "F.SilkS")
			(effects
				(font
					(size 0.7 0.7)
					(thickness 0.15)
				)
			)
		)
		(property "Value" "R_100k_0402"
			(at -1.011843 1.772047 270)
			(layer "F.Fab")
			(effects
				(font
					(size 0.7 0.7)
					(thickness 0.15)
				)
				(justify left bottom)
			)
		)
		(property "Datasheet" "https://www.bourns.com/docs/product-datasheets/cr.pdf"
			(at 0 0 270)
			(layer "F.Fab")
			(hide yes)
			(effects
				(font
					(size 1.27 1.27)
					(thickness 0.15)
				)
			)
		)
		(property "Description" "SMD Chip Resistor, 100 kohm, ± 1%, 62.5 mW, 0402 [1005 Metric], Thick Film, General Purpose"
			(at 0 0 270)
			(layer "F.Fab")
			(hide yes)
			(effects
				(font
					(size 1.27 1.27)
					(thickness 0.15)
				)
			)
		)
		(property "MPN" "CR0402-FX-1003GLF"
			(at 0 0 270)
			(unlocked yes)
			(layer "F.Fab")
			(hide yes)
			(effects
				(font
					(size 1 1)
					(thickness 0.15)
				)
			)
		)
		(property "Manufacturer" "Bourns"
			(at 0 0 270)
			(unlocked yes)
			(layer "F.Fab")
			(hide yes)
			(effects
				(font
					(size 1 1)
					(thickness 0.15)
				)
			)
		)
		(property "License" "Apache-2.0"
			(at 0 0 270)
			(unlocked yes)
			(layer "F.Fab")
			(hide yes)
			(effects
				(font
					(size 1 1)
					(thickness 0.15)
				)
			)
		)
		(property "Author" "Antmicro"
			(at 0 0 270)
			(unlocked yes)
			(layer "F.Fab")
			(hide yes)
			(effects
				(font
					(size 1 1)
					(thickness 0.15)
				)
			)
		)
		(property "Val" "100k"
			(at 0 0 270)
			(unlocked yes)
			(layer "F.Fab")
			(hide yes)
			(effects
				(font
					(size 1 1)
					(thickness 0.15)
				)
			)
		)
		(property "Tolerance" "1%"
			(at 0 0 270)
			(unlocked yes)
			(layer "F.Fab")
			(hide yes)
			(effects
				(font
					(size 1 1)
					(thickness 0.15)
				)
			)
		)
		(sheetname "/X710-AT2 Misc/")
		(sheetfile "x710-at2-mics.kicad_sch")
		(attr smd)
		(fp_rect
			(start -0.925 -0.47)
			(end 0.925 0.47)
			(stroke
				(width 0.05)
				(type default)
			)
			(fill no)
			(layer "F.CrtYd")
		)
		(fp_rect
			(start -0.5 -0.25)
			(end 0.5 0.25)
			(stroke
				(width 0.15)
				(type solid)
			)
			(fill no)
			(layer "F.Fab")
		)
		(fp_text user "Author: Antmicro"
			(at -0.95 4.169 270)
			(layer "F.Fab")
			(effects
				(font
					(size 0.7 0.7)
					(thickness 0.15)
				)
				(justify left bottom)
			)
		)
		(fp_text user "${REFERENCE}"
			(at -0.95 3.168 270)
			(layer "F.Fab")
			(effects
				(font
					(size 0.7 0.7)
					(thickness 0.15)
				)
				(justify left bottom)
			)
		)
		(fp_text user "License: Apache-2.0"
			(at -0.95 5.169 270)
			(layer "F.Fab")
			(effects
				(font
					(size 0.7 0.7)
					(thickness 0.15)
				)
				(justify left bottom)
			)
		)
		(pad "1" smd roundrect
			(at -0.48 0 270)
			(size 0.59 0.64)
			(layers "F.Cu" "F.Mask" "F.Paste")
			(roundrect_rratio 0.25)
			(net 137 "/X710-AT2 Misc/NCSI.RXD_1")
			(pintype "passive")
		)
		(pad "2" smd roundrect
			(at 0.48 0 270)
			(size 0.59 0.64)
			(layers "F.Cu" "F.Mask" "F.Paste")
			(roundrect_rratio 0.25)
			(net 7 "+3V3")
			(pintype "passive")
		)
	)
	(footprint "antmicro-footprints:C_0603_1608Metric_EIA"
		(layer "F.Cu")
		(at 138.705 89.274999 -90)
		(descr "Capacitor SMD 0603, IPC-7351 Density Level A")
		(tags "Capacitor 0603")
		(property "Reference" "C239"
			(at 4.225001 17.455 270)
			(layer "F.SilkS")
			(effects
				(font
					(size 0.7 0.7)
					(thickness 0.15)
				)
				(justify left bottom)
			)
		)
		(property "Value" "C_22u_16V_0603"
			(at -1.42757 1.770288 270)
			(layer "F.Fab")
			(effects
				(font
					(size 0.7 0.7)
					(thickness 0.15)
				)
				(justify left bottom)
			)
		)
		(property "Datasheet" "https://product.samsungsem.com/mlcc/CL10A226MO7JZN.do"
			(at 0 0 270)
			(layer "F.Fab")
			(hide yes)
			(effects
				(font
					(size 1.27 1.27)
					(thickness 0.15)
				)
			)
		)
		(property "Description" "SMD Multilayer Ceramic Capacitor"
			(at 0 0 270)
			(layer "F.Fab")
			(hide yes)
			(effects
				(font
					(size 1.27 1.27)
					(thickness 0.15)
				)
			)
		)
		(property "MPN" "CL10A226MO7JZNC"
			(at 0 0 270)
			(unlocked yes)
			(layer "F.Fab")
			(hide yes)
			(effects
				(font
					(size 1 1)
					(thickness 0.15)
				)
			)
		)
		(property "Manufacturer" "Samsung Electro-Mechanics"
			(at 0 0 270)
			(unlocked yes)
			(layer "F.Fab")
			(hide yes)
			(effects
				(font
					(size 1 1)
					(thickness 0.15)
				)
			)
		)
		(property "License" "Apache-2.0"
			(at 0 0 270)
			(unlocked yes)
			(layer "F.Fab")
			(hide yes)
			(effects
				(font
					(size 1 1)
					(thickness 0.15)
				)
			)
		)
		(property "Author" "Antmicro"
			(at 0 0 270)
			(unlocked yes)
			(layer "F.Fab")
			(hide yes)
			(effects
				(font
					(size 1 1)
					(thickness 0.15)
				)
			)
		)
		(property "Val" "22u"
			(at 0 0 270)
			(unlocked yes)
			(layer "F.Fab")
			(hide yes)
			(effects
				(font
					(size 1 1)
					(thickness 0.15)
				)
			)
		)
		(property "Voltage" "16V"
			(at 0 0 270)
			(unlocked yes)
			(layer "F.Fab")
			(hide yes)
			(effects
				(font
					(size 1 1)
					(thickness 0.15)
				)
			)
		)
		(property "Dielectric" ""
			(at 0 0 270)
			(unlocked yes)
			(layer "F.Fab")
			(hide yes)
			(effects
				(font
					(size 1 1)
					(thickness 0.15)
				)
			)
		)
		(sheetname "/X710-AT2 power/")
		(sheetfile "x710-at2-power.kicad_sch")
		(attr smd)
		(fp_line
			(start -0.15 0.55)
			(end 0.15 0.55)
			(stroke
				(width 0.15)
				(type solid)
			)
			(layer "F.SilkS")
		)
		(fp_line
			(start -0.15 -0.55)
			(end 0.15 -0.55)
			(stroke
				(width 0.15)
				(type solid)
			)
			(layer "F.SilkS")
		)
		(fp_rect
			(start -1.25 -0.65)
			(end 1.25 0.65)
			(stroke
				(width 0.05)
				(type solid)
			)
			(fill no)
			(layer "F.CrtYd")
		)
		(fp_rect
			(start -0.8 -0.45)
			(end 0.8 0.45)
			(stroke
				(width 0.15)
				(type solid)
			)
			(fill no)
			(layer "F.Fab")
		)
		(fp_text user "${REFERENCE}"
			(at -1.682 3.895 270)
			(layer "F.Fab")
			(effects
				(font
					(size 0.7 0.7)
					(thickness 0.15)
				)
				(justify left bottom)
			)
		)
		(fp_text user "License: Apache-2.0"
			(at -1.682 5.895 270)
			(layer "F.Fab")
			(effects
				(font
					(size 0.7 0.7)
					(thickness 0.15)
				)
				(justify left bottom)
			)
		)
		(fp_text user "Author: Antmicro"
			(at -1.682 4.894 270)
			(layer "F.Fab")
			(effects
				(font
					(size 0.7 0.7)
					(thickness 0.15)
				)
				(justify left bottom)
			)
		)
		(pad "1" smd roundrect
			(at -0.7 0 270)
			(size 0.8 1.1)
			(layers "F.Cu" "F.Mask" "F.Paste")
			(roundrect_rratio 0.2)
			(net 23 "GND")
			(pintype "passive")
		)
		(pad "2" smd roundrect
			(at 0.7 0 270)
			(size 0.8 1.1)
			(layers "F.Cu" "F.Mask" "F.Paste")
			(roundrect_rratio 0.2)
			(net 7 "+3V3")
			(pintype "passive")
		)
	)
)
